(kicad_pcb
	(version 20260206)
	(generator "pcbnew")
	(generator_version "10.0")
	(general
		(thickness 1.6)
		(legacy_teardrops no)
	)
	(paper "A4")
	(title_block
		(title "baseboard — 13948-1b.1110WZS1818.brd")
		(comment 1 "Honey Badger (Wiwynn) / footprints 10-15 of 2523")
	)
	(layers
		(0 "F.Cu" signal "TOP")
		(4 "In1.Cu" signal "L2GND")
		(6 "In2.Cu" signal "L3")
		(8 "In3.Cu" signal "L4VCC")
		(10 "In4.Cu" signal "L5VCC")
		(12 "In5.Cu" signal "L6")
		(14 "In6.Cu" signal "L7GND")
		(2 "B.Cu" signal "BOTTOM")
		(9 "F.Adhes" user "F.Adhesive")
		(11 "B.Adhes" user "B.Adhesive")
		(13 "F.Paste" user "Package Geometry/Pastemask Top")
		(15 "B.Paste" user "Package Geometry/Pastemask Bottom")
		(5 "F.SilkS" user "Ref Des/Silkscreen Top")
		(7 "B.SilkS" user "Ref Des/Silkscreen Bottom")
		(1 "F.Mask" user "Board Geometry/Soldermask Top")
		(3 "B.Mask" user "Board Geometry/Soldermask Bottom")
		(17 "Dwgs.User" user "User.Drawings")
		(19 "Cmts.User" user "User.Comments")
		(21 "Eco1.User" user "User.Eco1")
		(23 "Eco2.User" user "User.Eco2")
		(25 "Edge.Cuts" user "Board Geometry/Outline")
		(27 "Margin" user)
		(31 "F.CrtYd" user "Package Geometry/Place Bound Top")
		(29 "B.CrtYd" user "Package Geometry/Place Bound Bottom")
		(35 "F.Fab" user "Ref Des/Assembly Top")
		(33 "B.Fab" user "Ref Des/Assembly Bottom")
	)
	(footprint ""
		(layer "F.Cu")
		(at 183.4388 -51.308 -90)
		(property "Reference" "C312"
			(at 0 0 270)
			(layer "F.SilkS")
			(hide yes)
			(effects
				(font
					(size 1.27 1.27)
				)
			)
		)
		(property "Value" "SCD1U25V3KX-GP"
			(at 0 -2.8194 270)
			(unlocked yes)
			(layer "F.Fab")
			(hide yes)
			(effects
				(font
					(size 1.016 1.016)
					(thickness 0.1524)
				)
			)
		)
		(property "Device Type" "C603H36"
			(at 0 -4.3434 270)
			(unlocked yes)
			(layer "F.Fab")
			(hide yes)
			(effects
				(font
					(size 1.016 1.016)
					(thickness 0.1524)
				)
			)
		)
		(duplicate_pad_numbers_are_jumpers no)
		(fp_line
			(start 0.508 0)
			(end -0.508 0)
			(stroke
				(width 0.2032)
				(type default)
			)
			(layer "F.SilkS")
		)
		(fp_rect
			(start -0.5842 1.3335)
			(end 0.5842 -1.3335)
			(stroke
				(width 0)
				(type default)
			)
			(fill no)
			(layer "F.CrtYd")
		)
		(fp_rect
			(start -0.5842 1.3335)
			(end 0.5842 -1.3335)
			(stroke
				(width 0)
				(type default)
			)
			(fill no)
			(layer "F.Fab")
		)
		(pad "1" smd custom
			(at 0 -0.762 270)
			(size 0.2159 0.2159)
			(layers "F.Cu" "F.Mask" "F.Paste")
			(net "PRSNT_AND_2")
			(options
				(clearance outline)
				(anchor circle)
			)
			(primitives
				(gr_poly
					(pts
						(arc
							(start -0.3302 -0.4318)
							(mid -0.402042 -0.402042)
							(end -0.4318 -0.3302)
						)
						(arc
							(start -0.4318 0.3302)
							(mid -0.402042 0.402042)
							(end -0.3302 0.4318)
						)
						(arc
							(start 0.3302 0.4318)
							(mid 0.402042 0.402042)
							(end 0.4318 0.3302)
						)
						(arc
							(start 0.4318 -0.3302)
							(mid 0.402042 -0.402042)
							(end 0.3302 -0.4318)
						)
					)
					(width 0)
					(fill yes)
				)
			)
		)
		(pad "2" smd custom
			(at 0 0.762 270)
			(size 0.2159 0.2159)
			(layers "F.Cu" "F.Mask" "F.Paste")
			(net "GND")
			(options
				(clearance outline)
				(anchor circle)
			)
			(primitives
				(gr_poly
					(pts
						(arc
							(start -0.3302 -0.4318)
							(mid -0.402042 -0.402042)
							(end -0.4318 -0.3302)
						)
						(arc
							(start -0.4318 0.3302)
							(mid -0.402042 0.402042)
							(end -0.3302 0.4318)
						)
						(arc
							(start 0.3302 0.4318)
							(mid 0.402042 0.402042)
							(end 0.4318 0.3302)
						)
						(arc
							(start 0.4318 -0.3302)
							(mid 0.402042 -0.402042)
							(end 0.3302 -0.4318)
						)
					)
					(width 0)
					(fill yes)
				)
			)
		)
	)
	(footprint ""
		(layer "F.Cu")
		(at 274.193 -168.021 90)
		(property "Reference" "R448"
			(at 0 0 90)
			(layer "F.SilkS")
			(hide yes)
			(effects
				(font
					(size 1.27 1.27)
				)
			)
		)
		(property "Value" "10KR2F-2-GP"
			(at 0.064008 -3.993896 90)
			(unlocked yes)
			(layer "F.Fab")
			(hide yes)
			(effects
				(font
					(size 1.016 1.016)
					(thickness 0.1524)
				)
			)
		)
		(property "Device Type" "R402H16"
			(at 0.064008 -5.517896 90)
			(unlocked yes)
			(layer "F.Fab")
			(hide yes)
			(effects
				(font
					(size 1.016 1.016)
					(thickness 0.1524)
				)
			)
		)
		(duplicate_pad_numbers_are_jumpers no)
		(fp_line
			(start 0.508 -0.9398)
			(end -0.508 -0.9398)
			(stroke
				(width 0.1524)
				(type default)
			)
			(layer "F.SilkS")
		)
		(fp_line
			(start -0.508 -0.9398)
			(end -0.508 0.9398)
			(stroke
				(width 0.1524)
				(type default)
			)
			(layer "F.SilkS")
		)
		(fp_rect
			(start -0.508 0.9398)
			(end 0.508 -0.9398)
			(stroke
				(width 0)
				(type default)
			)
			(fill no)
			(layer "F.CrtYd")
		)
		(fp_rect
			(start -0.508 0.9398)
			(end 0.508 -0.9398)
			(stroke
				(width 0)
				(type default)
			)
			(fill no)
			(layer "F.Fab")
		)
		(pad "1" smd custom
			(at 0 -0.4445 90)
			(size 0.1397 0.1397)
			(layers "F.Cu" "F.Mask" "F.Paste")
			(net "P3V3_STBY")
			(options
				(clearance outline)
				(anchor circle)
			)
			(primitives
				(gr_poly
					(pts
						(arc
							(start -0.1778 -0.2794)
							(mid -0.249642 -0.249642)
							(end -0.2794 -0.1778)
						)
						(arc
							(start -0.2794 0.1778)
							(mid -0.249642 0.249642)
							(end -0.1778 0.2794)
						)
						(arc
							(start 0.1778 0.2794)
							(mid 0.249642 0.249642)
							(end 0.2794 0.1778)
						)
						(arc
							(start 0.2794 -0.1778)
							(mid 0.249642 -0.249642)
							(end 0.1778 -0.2794)
						)
					)
					(width 0)
					(fill yes)
				)
			)
		)
		(pad "2" smd custom
			(at 0 0.4445 90)
			(size 0.1397 0.1397)
			(layers "F.Cu" "F.Mask" "F.Paste")
			(net "I2C_BMC_10G_ALERT#")
			(options
				(clearance outline)
				(anchor circle)
			)
			(primitives
				(gr_poly
					(pts
						(arc
							(start -0.1778 -0.2794)
							(mid -0.249642 -0.249642)
							(end -0.2794 -0.1778)
						)
						(arc
							(start -0.2794 0.1778)
							(mid -0.249642 0.249642)
							(end -0.1778 0.2794)
						)
						(arc
							(start 0.1778 0.2794)
							(mid 0.249642 0.249642)
							(end 0.2794 0.1778)
						)
						(arc
							(start 0.2794 -0.1778)
							(mid 0.249642 -0.249642)
							(end 0.1778 -0.2794)
						)
					)
					(width 0)
					(fill yes)
				)
			)
		)
	)
	(footprint ""
		(layer "F.Cu")
		(at 193.802 -116.205)
		(property "Reference" "PR7889"
			(at 0 0 0)
			(layer "F.SilkS")
			(hide yes)
			(effects
				(font
					(size 1.27 1.27)
				)
			)
		)
		(property "Value" "4K75R2F-1-GP"
			(at 0.064008 -3.993896 0)
			(unlocked yes)
			(layer "F.Fab")
			(hide yes)
			(effects
				(font
					(size 1.016 1.016)
					(thickness 0.1524)
				)
			)
		)
		(property "Device Type" "R402H16"
			(at 0.064008 -5.517896 0)
			(unlocked yes)
			(layer "F.Fab")
			(hide yes)
			(effects
				(font
					(size 1.016 1.016)
					(thickness 0.1524)
				)
			)
		)
		(duplicate_pad_numbers_are_jumpers no)
		(fp_line
			(start -0.508 -0.9398)
			(end -0.508 0.9398)
			(stroke
				(width 0.1524)
				(type default)
			)
			(layer "F.SilkS")
		)
		(fp_line
			(start 0.508 -0.9398)
			(end -0.508 -0.9398)
			(stroke
				(width 0.1524)
				(type default)
			)
			(layer "F.SilkS")
		)
		(fp_rect
			(start -0.508 0.9398)
			(end 0.508 -0.9398)
			(stroke
				(width 0)
				(type default)
			)
			(fill no)
			(layer "F.CrtYd")
		)
		(fp_rect
			(start -0.508 0.9398)
			(end 0.508 -0.9398)
			(stroke
				(width 0)
				(type default)
			)
			(fill no)
			(layer "F.Fab")
		)
		(pad "1" smd custom
			(at 0 -0.4445)
			(size 0.1397 0.1397)
			(layers "F.Cu" "F.Mask" "F.Paste")
			(net "P3V3_STBY")
			(options
				(clearance outline)
				(anchor circle)
			)
			(primitives
				(gr_poly
					(pts
						(arc
							(start -0.1778 -0.2794)
							(mid -0.249642 -0.249642)
							(end -0.2794 -0.1778)
						)
						(arc
							(start -0.2794 0.1778)
							(mid -0.249642 0.249642)
							(end -0.1778 0.2794)
						)
						(arc
							(start 0.1778 0.2794)
							(mid 0.249642 0.249642)
							(end 0.2794 0.1778)
						)
						(arc
							(start 0.2794 -0.1778)
							(mid 0.249642 -0.249642)
							(end 0.1778 -0.2794)
						)
					)
					(width 0)
					(fill yes)
				)
			)
		)
		(pad "2" smd custom
			(at 0 0.4445)
			(size 0.1397 0.1397)
			(layers "F.Cu" "F.Mask" "F.Paste")
			(net "P1V5_E_EN_R")
			(options
				(clearance outline)
				(anchor circle)
			)
			(primitives
				(gr_poly
					(pts
						(arc
							(start -0.1778 -0.2794)
							(mid -0.249642 -0.249642)
							(end -0.2794 -0.1778)
						)
						(arc
							(start -0.2794 0.1778)
							(mid -0.249642 0.249642)
							(end -0.1778 0.2794)
						)
						(arc
							(start 0.1778 0.2794)
							(mid 0.249642 0.249642)
							(end 0.2794 0.1778)
						)
						(arc
							(start 0.2794 -0.1778)
							(mid 0.249642 -0.249642)
							(end 0.1778 -0.2794)
						)
					)
					(width 0)
					(fill yes)
				)
			)
		)
	)
	(footprint ""
		(layer "F.Cu")
		(at 32.424116 -76.442062 180)
		(property "Reference" "R673"
			(at 0 0 180)
			(layer "F.SilkS")
			(hide yes)
			(effects
				(font
					(size 1.27 1.27)
				)
			)
		)
		(property "Value" "300R3F-GP"
			(at -0.0254 -2.5146 180)
			(unlocked yes)
			(layer "F.Fab")
			(hide yes)
			(effects
				(font
					(size 1.016 1.016)
					(thickness 0.1524)
				)
			)
		)
		(property "Device Type" "R603H22"
			(at -0.0254 -4.0386 180)
			(unlocked yes)
			(layer "F.Fab")
			(hide yes)
			(effects
				(font
					(size 1.016 1.016)
					(thickness 0.1524)
				)
			)
		)
		(duplicate_pad_numbers_are_jumpers no)
		(fp_line
			(start 0.2032 0)
			(end 0.4826 0)
			(stroke
				(width 0.2032)
				(type default)
			)
			(layer "F.SilkS")
		)
		(fp_line
			(start -0.4826 0)
			(end -0.2032 0)
			(stroke
				(width 0.2032)
				(type default)
			)
			(layer "F.SilkS")
		)
		(fp_rect
			(start -0.5842 1.3335)
			(end 0.5842 -1.3335)
			(stroke
				(width 0)
				(type default)
			)
			(fill no)
			(layer "F.CrtYd")
		)
		(fp_rect
			(start -0.5842 1.3335)
			(end 0.5842 -1.3335)
			(stroke
				(width 0)
				(type default)
			)
			(fill no)
			(layer "F.Fab")
		)
		(pad "1" smd custom
			(at 0 -0.762 180)
			(size 0.2159 0.2159)
			(layers "F.Cu" "F.Mask" "F.Paste")
			(net "P3V3_STBY")
			(options
				(clearance outline)
				(anchor circle)
			)
			(primitives
				(gr_poly
					(pts
						(arc
							(start -0.3302 -0.4318)
							(mid -0.402042 -0.402042)
							(end -0.4318 -0.3302)
						)
						(arc
							(start -0.4318 0.3302)
							(mid -0.402042 0.402042)
							(end -0.3302 0.4318)
						)
						(arc
							(start 0.3302 0.4318)
							(mid 0.402042 0.402042)
							(end 0.4318 0.3302)
						)
						(arc
							(start 0.4318 -0.3302)
							(mid 0.402042 -0.402042)
							(end 0.3302 -0.4318)
						)
					)
					(width 0)
					(fill yes)
				)
			)
		)
		(pad "2" smd custom
			(at 0 0.762 180)
			(size 0.2159 0.2159)
			(layers "F.Cu" "F.Mask" "F.Paste")
			(net "INTA_LED_RED_C")
			(options
				(clearance outline)
				(anchor circle)
			)
			(primitives
				(gr_poly
					(pts
						(arc
							(start -0.3302 -0.4318)
							(mid -0.402042 -0.402042)
							(end -0.4318 -0.3302)
						)
						(arc
							(start -0.4318 0.3302)
							(mid -0.402042 0.402042)
							(end -0.3302 0.4318)
						)
						(arc
							(start 0.3302 0.4318)
							(mid 0.402042 0.402042)
							(end 0.4318 0.3302)
						)
						(arc
							(start 0.4318 -0.3302)
							(mid 0.402042 -0.402042)
							(end 0.3302 -0.4318)
						)
					)
					(width 0)
					(fill yes)
				)
			)
		)
	)
	(footprint ""
		(layer "F.Cu")
		(at 271.999964 -8.279892)
		(property "Reference" "SKT1"
			(at 0 0 0)
			(layer "F.SilkS")
			(hide yes)
			(effects
				(font
					(size 1.27 1.27)
				)
			)
		)
		(property "Value" "SKT-USB-250-GP"
			(at -10.033 -1.3716 0)
			(unlocked yes)
			(layer "F.Fab")
			(hide yes)
			(effects
				(font
					(size 1.016 1.016)
					(thickness 0.1524)
				)
			)
		)
		(property "Device Type" "67643-3911"
			(at -10.033 -2.8956 0)
			(unlocked yes)
			(layer "F.Fab")
			(hide yes)
			(effects
				(font
					(size 1.016 1.016)
					(thickness 0.1524)
				)
			)
		)
		(duplicate_pad_numbers_are_jumpers no)
		(fp_line
			(start -8.1788 -1.4605)
			(end -7.4549 -1.4605)
			(stroke
				(width 0.1524)
				(type default)
			)
			(layer "F.SilkS")
		)
		(fp_line
			(start -8.1788 1.4605)
			(end -8.1788 -1.4605)
			(stroke
				(width 0.1524)
				(type default)
			)
			(layer "F.SilkS")
		)
		(fp_line
			(start -7.4549 -5.2324)
			(end 7.4549 -5.2324)
			(stroke
				(width 0.1524)
				(type default)
			)
			(layer "F.SilkS")
		)
		(fp_line
			(start -7.4549 -1.4605)
			(end -7.4549 -5.2324)
			(stroke
				(width 0.1524)
				(type default)
			)
			(layer "F.SilkS")
		)
		(fp_line
			(start -7.4549 1.4605)
			(end -8.1788 1.4605)
			(stroke
				(width 0.1524)
				(type default)
			)
			(layer "F.SilkS")
		)
		(fp_line
			(start -7.4549 10.279888)
			(end 7.4549 10.279888)
			(stroke
				(width 0.1524)
				(type default)
			)
			(layer "F.SilkS")
		)
		(fp_line
			(start -7.4549 10.541)
			(end -7.4549 1.4605)
			(stroke
				(width 0.1524)
				(type default)
			)
			(layer "F.SilkS")
		)
		(fp_line
			(start 7.4549 -5.2324)
			(end 7.4549 -1.4605)
			(stroke
				(width 0.1524)
				(type default)
			)
			(layer "F.SilkS")
		)
		(fp_line
			(start 7.4549 -1.4605)
			(end 8.1788 -1.4605)
			(stroke
				(width 0.1524)
				(type default)
			)
			(layer "F.SilkS")
		)
		(fp_line
			(start 7.4549 1.4605)
			(end 7.4549 10.541)
			(stroke
				(width 0.1524)
				(type default)
			)
			(layer "F.SilkS")
		)
		(fp_line
			(start 7.4549 10.541)
			(end -7.4549 10.541)
			(stroke
				(width 0.1524)
				(type default)
			)
			(layer "F.SilkS")
		)
		(fp_line
			(start 8.1788 -1.4605)
			(end 8.1788 1.4605)
			(stroke
				(width 0.1524)
				(type default)
			)
			(layer "F.SilkS")
		)
		(fp_line
			(start 8.1788 1.4605)
			(end 7.4549 1.4605)
			(stroke
				(width 0.1524)
				(type default)
			)
			(layer "F.SilkS")
		)
		(fp_arc
			(start 0 -3.000756)
			(mid 2.041429 -2.709926)
			(end 0 -2.419096)
			(stroke
				(width 0.3048)
				(type default)
			)
			(layer "F.SilkS")
		)
		(fp_arc
			(start 0 -2.419096)
			(mid -2.041429 -2.709926)
			(end 0 -3.000756)
			(stroke
				(width 0.3048)
				(type default)
			)
			(layer "F.SilkS")
		)
		(fp_circle
			(center -6.569964 0)
			(end -4.855464 0)
			(stroke
				(width 0.3048)
				(type default)
			)
			(fill no)
			(layer "F.SilkS")
		)
		(fp_circle
			(center -3.50012 -2.709926)
			(end -2.45872 -2.709926)
			(stroke
				(width 0.3048)
				(type default)
			)
			(fill no)
			(layer "F.SilkS")
		)
		(fp_circle
			(center 3.50012 -2.709926)
			(end 4.54152 -2.709926)
			(stroke
				(width 0.3048)
				(type default)
			)
			(fill no)
			(layer "F.SilkS")
		)
		(fp_circle
			(center 6.569964 0)
			(end 8.284464 0)
			(stroke
				(width 0.3048)
				(type default)
			)
			(fill no)
			(layer "F.SilkS")
		)
		(fp_poly
			(pts
				(xy -7.2009 10.287) (xy -7.2009 0.7493) (xy -7.8486 0.7493) (xy -7.8486 -0.7493) (xy -7.2009 -0.7493)
				(xy -7.2009 -4.9784) (xy 7.2009 -4.9784) (xy 7.2009 -0.7493) (xy 7.8486 -0.7493) (xy 7.8486 0.7493)
				(xy 7.2009 0.7493) (xy 7.2009 10.287)
			)
			(stroke
				(width 0)
				(type default)
			)
			(fill no)
			(layer "F.CrtYd")
		)
		(fp_poly
			(pts
				(xy -7.2009 10.287) (xy -7.2009 0.7493) (xy -7.8486 0.7493) (xy -7.8486 -0.7493) (xy -7.2009 -0.7493)
				(xy -7.2009 -4.9784) (xy 7.2009 -4.9784) (xy 7.2009 -4.4323) (xy 7.7089 -4.4323) (xy 7.7089 -5.4864)
				(xy -7.7089 -5.4864) (xy -7.7089 -1.7145) (xy -8.4328 -1.7145) (xy -8.4328 1.7145) (xy -7.7089 1.7145)
				(xy -7.7089 10.795) (xy 7.7089 10.795) (xy 7.7089 1.7145) (xy 8.4328 1.7145) (xy 8.4328 -1.7145)
				(xy 7.7089 -1.7145) (xy 7.7089 -4.4196) (xy 7.2009 -4.4196) (xy 7.2009 -0.7493) (xy 7.8486 -0.7493)
				(xy 7.8486 0.7493) (xy 7.2009 0.7493) (xy 7.2009 10.287)
			)
			(stroke
				(width 0)
				(type default)
			)
			(fill no)
			(layer "F.CrtYd")
		)
		(fp_poly
			(pts
				(xy -7.7089 10.795) (xy -7.7089 1.7145) (xy -8.4328 1.7145) (xy -8.4328 -1.7145) (xy -7.7089 -1.7145)
				(xy -7.7089 -5.4864) (xy 7.7089 -5.4864) (xy 7.7089 -1.7145) (xy 8.4328 -1.7145) (xy 8.4328 1.7145)
				(xy 7.7089 1.7145) (xy 7.7089 10.795)
			)
			(stroke
				(width 0)
				(type default)
			)
			(fill no)
			(layer "F.Fab")
		)
		(pad "1" thru_hole circle
			(at -3.50012 -2.709926)
			(size 1.3716 1.3716)
			(drill 0.9652)
			(layers "*.Cu" "*.Mask")
			(remove_unused_layers no)
			(net "P5V_USB")
			(clearance 0.1524)
			(thermal_gap 0.1524)
		)
		(pad "2" thru_hole circle
			(at -0.999998 -2.709926)
			(size 1.3716 1.3716)
			(drill 0.9652)
			(layers "*.Cu" "*.Mask")
			(remove_unused_layers no)
			(net "USB_P1_F_DN1")
			(clearance 0.1524)
			(thermal_gap 0.1524)
		)
		(pad "3" thru_hole circle
			(at 0.999998 -2.709926)
			(size 1.3716 1.3716)
			(drill 0.9652)
			(layers "*.Cu" "*.Mask")
			(remove_unused_layers no)
			(net "USB_P1_F_DP1")
			(clearance 0.1524)
			(thermal_gap 0.1524)
		)
		(pad "4" thru_hole circle
			(at 3.50012 -2.709926)
			(size 1.3716 1.3716)
			(drill 0.9652)
			(layers "*.Cu" "*.Mask")
			(remove_unused_layers no)
			(net "GND")
			(clearance 0.1524)
			(thermal_gap 0.1524)
		)
		(pad "5" thru_hole circle
			(at 6.569964 0)
			(size 2.7178 2.7178)
			(drill 2.3114)
			(layers "*.Cu" "*.Mask")
			(remove_unused_layers no)
			(net "AGND_USB")
			(clearance 0.1524)
			(thermal_gap 0.1524)
		)
		(pad "6" thru_hole circle
			(at -6.569964 0)
			(size 2.7178 2.7178)
			(drill 2.3114)
			(layers "*.Cu" "*.Mask")
			(remove_unused_layers no)
			(net "AGND_USB")
			(clearance 0.1524)
			(thermal_gap 0.1524)
		)
	)
	(footprint ""
		(layer "F.Cu")
		(at 335.661 -108.458 90)
		(property "Reference" "PR15"
			(at 0 0 90)
			(layer "F.SilkS")
			(hide yes)
			(effects
				(font
					(size 1.27 1.27)
				)
			)
		)
		(property "Value" "3D01R5F-GP"
			(at 0 -8.9535 90)
			(unlocked yes)
			(layer "F.Fab")
			(hide yes)
			(effects
				(font
					(size 1.27 1.016)
					(thickness 0.1524)
				)
			)
		)
		(property "Device Type" "R805H24"
			(at 0 -10.6299 90)
			(unlocked yes)
			(layer "F.Fab")
			(hide yes)
			(effects
				(font
					(size 1.27 1.016)
					(thickness 0.1524)
				)
			)
		)
		(duplicate_pad_numbers_are_jumpers no)
		(fp_line
			(start 0.889 -1.7018)
			(end -0.889 -1.7018)
			(stroke
				(width 0.1524)
				(type default)
			)
			(layer "F.SilkS")
		)
		(fp_line
			(start 0.889 -1.7018)
			(end 0.889 -0.381)
			(stroke
				(width 0.1524)
				(type default)
			)
			(layer "F.SilkS")
		)
		(fp_line
			(start -0.889 -1.7018)
			(end -0.889 0.2794)
			(stroke
				(width 0.1524)
				(type default)
			)
			(layer "F.SilkS")
		)
		(fp_line
			(start -0.889 0.0762)
			(end -0.889 1.7018)
			(stroke
				(width 0.1524)
				(type default)
			)
			(layer "F.SilkS")
		)
		(fp_line
			(start 0.889 1.7018)
			(end 0.889 -0.508)
			(stroke
				(width 0.1524)
				(type default)
			)
			(layer "F.SilkS")
		)
		(fp_line
			(start -0.889 1.7018)
			(end 0.889 1.7018)
			(stroke
				(width 0.1524)
				(type default)
			)
			(layer "F.SilkS")
		)
		(fp_poly
			(pts
				(xy 0.9652 -1.778) (xy 0.9652 1.778) (xy -0.9652 1.778) (xy -0.9652 -1.778)
			)
			(stroke
				(width 0)
				(type default)
			)
			(fill no)
			(layer "F.CrtYd")
		)
		(fp_rect
			(start -0.9652 1.778)
			(end 0.9652 -1.778)
			(stroke
				(width 0)
				(type default)
			)
			(fill no)
			(layer "F.Fab")
		)
		(pad "1" smd rect
			(at 0 -0.9652 90)
			(size 1.397 1.143)
			(layers "F.Cu" "F.Mask" "F.Paste")
			(net "P5V_STBY__SNB")
		)
		(pad "2" smd rect
			(at 0 0.9652 90)
			(size 1.397 1.143)
			(layers "F.Cu" "F.Mask" "F.Paste")
			(net "GND")
		)
	)
)
